(kicad_pcb
	(version 20260206)
	(generator "pcbnew")
	(generator_version "10.0")
	(general
		(thickness 1.6)
		(legacy_teardrops no)
	)
	(paper "A4")
	(title_block
		(title "03242023_DA0F0TMBIJ0_F0T_Motherboard_J_brd_V01_OCP.brd")
		(comment 1 "Grand Teton / footprints 1844-1850 of 6105")
	)
	(layers
		(0 "F.Cu" signal "TOP")
		(4 "In1.Cu" signal "GND")
		(6 "In2.Cu" signal "IN1")
		(8 "In3.Cu" signal "GND1")
		(10 "In4.Cu" signal "IN2")
		(12 "In5.Cu" signal "GND2")
		(14 "In6.Cu" signal "IN3")
		(16 "In7.Cu" signal "GND3")
		(18 "In8.Cu" signal "VCC")
		(20 "In9.Cu" signal "VCC1")
		(22 "In10.Cu" signal "GND4")
		(24 "In11.Cu" signal "IN4")
		(26 "In12.Cu" signal "GND5")
		(28 "In13.Cu" signal "IN5")
		(30 "In14.Cu" signal "GND6")
		(32 "In15.Cu" signal "IN6")
		(34 "In16.Cu" signal "GND7")
		(2 "B.Cu" signal "BOTTOM")
		(9 "F.Adhes" user "F.Adhesive")
		(11 "B.Adhes" user "B.Adhesive")
		(13 "F.Paste" user "Package Geometry/Pastemask Top")
		(15 "B.Paste" user "Package Geometry/Pastemask Bottom")
		(5 "F.SilkS" user "Ref Des/Silkscreen Top")
		(7 "B.SilkS" user "Ref Des/Silkscreen Bottom")
		(1 "F.Mask" user "Board Geometry/Soldermask Top")
		(3 "B.Mask" user "Board Geometry/Soldermask Bottom")
		(17 "Dwgs.User" user "User.Drawings")
		(19 "Cmts.User" user "User.Comments")
		(21 "Eco1.User" user "User.Eco1")
		(23 "Eco2.User" user "User.Eco2")
		(25 "Edge.Cuts" user "Board Geometry/Outline")
		(27 "Margin" user)
		(31 "F.CrtYd" user "Package Geometry/Place Bound Top")
		(29 "B.CrtYd" user "Package Geometry/Place Bound Bottom")
		(35 "F.Fab" user "Ref Des/Assembly Top")
		(33 "B.Fab" user "Ref Des/Assembly Bottom")
	)
	(footprint ""
		(layer "F.Cu")
		(at 39.26332 -400.153886 -90)
		(property "Reference" "R4649"
			(at 0 0 270)
			(layer "F.SilkS")
			(hide yes)
			(effects
				(font
					(size 1.27 1.27)
				)
			)
		)
		(property "Value" ""
			(at 0 0 270)
			(layer "F.Fab")
			(effects
				(font
					(size 1.27 1.27)
				)
			)
		)
		(duplicate_pad_numbers_are_jumpers no)
		(fp_line
			(start -0.7874 0.4064)
			(end -0.7874 -0.4064)
			(stroke
				(width 0.1524)
				(type default)
			)
			(layer "F.SilkS")
		)
		(fp_line
			(start 0.7874 0.4064)
			(end -0.7874 0.4064)
			(stroke
				(width 0.1524)
				(type default)
			)
			(layer "F.SilkS")
		)
		(fp_line
			(start -0.7874 -0.4064)
			(end 0.7874 -0.4064)
			(stroke
				(width 0.1524)
				(type default)
			)
			(layer "F.SilkS")
		)
		(fp_line
			(start 0.7874 -0.4064)
			(end 0.7874 0.4064)
			(stroke
				(width 0.1524)
				(type default)
			)
			(layer "F.SilkS")
		)
		(fp_line
			(start -0.67945 0.3048)
			(end -0.67945 -0.305054)
			(stroke
				(width 0.1)
				(type default)
			)
			(layer "F.Fab")
		)
		(fp_line
			(start -0.12065 0.3048)
			(end -0.67945 0.3048)
			(stroke
				(width 0.1)
				(type default)
			)
			(layer "F.Fab")
		)
		(fp_line
			(start 0.120396 0.3048)
			(end 0.120396 0.2794)
			(stroke
				(width 0.1)
				(type default)
			)
			(layer "F.Fab")
		)
		(fp_line
			(start 0.67945 0.3048)
			(end 0.120396 0.3048)
			(stroke
				(width 0.1)
				(type default)
			)
			(layer "F.Fab")
		)
		(fp_line
			(start -0.12065 0.2794)
			(end -0.12065 0.3048)
			(stroke
				(width 0.1)
				(type default)
			)
			(layer "F.Fab")
		)
		(fp_line
			(start 0.120396 0.2794)
			(end -0.12065 0.2794)
			(stroke
				(width 0.1)
				(type default)
			)
			(layer "F.Fab")
		)
		(fp_line
			(start -0.12065 -0.2794)
			(end 0.12065 -0.2794)
			(stroke
				(width 0.1)
				(type default)
			)
			(layer "F.Fab")
		)
		(fp_line
			(start 0.12065 -0.2794)
			(end 0.12065 -0.3048)
			(stroke
				(width 0.1)
				(type default)
			)
			(layer "F.Fab")
		)
		(fp_line
			(start 0.12065 -0.3048)
			(end 0.67945 -0.3048)
			(stroke
				(width 0.1)
				(type default)
			)
			(layer "F.Fab")
		)
		(fp_line
			(start 0.67945 -0.3048)
			(end 0.67945 0.3048)
			(stroke
				(width 0.1)
				(type default)
			)
			(layer "F.Fab")
		)
		(fp_line
			(start -0.67945 -0.305054)
			(end -0.12065 -0.305054)
			(stroke
				(width 0.1)
				(type default)
			)
			(layer "F.Fab")
		)
		(fp_line
			(start -0.12065 -0.305054)
			(end -0.12065 -0.2794)
			(stroke
				(width 0.1)
				(type default)
			)
			(layer "F.Fab")
		)
		(pad "1" smd circle
			(at -0.40005 0 270)
			(size 0 0)
			(layers "F.Cu" "F.Mask" "F.Paste")
			(net "P3V3_AUX")
		)
		(pad "2" smd circle
			(at 0.40005 0 270)
			(size 0 0)
			(layers "F.Cu" "F.Mask" "F.Paste")
			(net "FM_P2E_BUF2_EQA0")
		)
	)
	(footprint ""
		(layer "F.Cu")
		(at 387.633972 -29.10967 -90)
		(property "Reference" "C188"
			(at 0 0 270)
			(layer "F.SilkS")
			(hide yes)
			(effects
				(font
					(size 1.27 1.27)
				)
			)
		)
		(property "Value" ""
			(at 0 0 270)
			(layer "F.Fab")
			(effects
				(font
					(size 1.27 1.27)
				)
			)
		)
		(duplicate_pad_numbers_are_jumpers no)
		(fp_line
			(start -0.7874 0.4064)
			(end -0.7874 -0.4064)
			(stroke
				(width 0.1524)
				(type default)
			)
			(layer "F.SilkS")
		)
		(fp_line
			(start 0.7874 0.4064)
			(end -0.7874 0.4064)
			(stroke
				(width 0.1524)
				(type default)
			)
			(layer "F.SilkS")
		)
		(fp_line
			(start -0.7874 -0.4064)
			(end 0.7874 -0.4064)
			(stroke
				(width 0.1524)
				(type default)
			)
			(layer "F.SilkS")
		)
		(fp_line
			(start 0.7874 -0.4064)
			(end 0.7874 0.4064)
			(stroke
				(width 0.1524)
				(type default)
			)
			(layer "F.SilkS")
		)
		(fp_line
			(start -0.67945 0.3048)
			(end -0.67945 -0.305054)
			(stroke
				(width 0.1)
				(type default)
			)
			(layer "F.Fab")
		)
		(fp_line
			(start -0.12065 0.3048)
			(end -0.67945 0.3048)
			(stroke
				(width 0.1)
				(type default)
			)
			(layer "F.Fab")
		)
		(fp_line
			(start 0.120396 0.3048)
			(end 0.120396 0.2794)
			(stroke
				(width 0.1)
				(type default)
			)
			(layer "F.Fab")
		)
		(fp_line
			(start 0.67945 0.3048)
			(end 0.120396 0.3048)
			(stroke
				(width 0.1)
				(type default)
			)
			(layer "F.Fab")
		)
		(fp_line
			(start -0.12065 0.2794)
			(end -0.12065 0.3048)
			(stroke
				(width 0.1)
				(type default)
			)
			(layer "F.Fab")
		)
		(fp_line
			(start 0.120396 0.2794)
			(end -0.12065 0.2794)
			(stroke
				(width 0.1)
				(type default)
			)
			(layer "F.Fab")
		)
		(fp_line
			(start -0.12065 -0.2794)
			(end 0.12065 -0.2794)
			(stroke
				(width 0.1)
				(type default)
			)
			(layer "F.Fab")
		)
		(fp_line
			(start 0.12065 -0.2794)
			(end 0.12065 -0.3048)
			(stroke
				(width 0.1)
				(type default)
			)
			(layer "F.Fab")
		)
		(fp_line
			(start 0.12065 -0.3048)
			(end 0.67945 -0.3048)
			(stroke
				(width 0.1)
				(type default)
			)
			(layer "F.Fab")
		)
		(fp_line
			(start 0.67945 -0.3048)
			(end 0.67945 0.3048)
			(stroke
				(width 0.1)
				(type default)
			)
			(layer "F.Fab")
		)
		(fp_line
			(start -0.67945 -0.305054)
			(end -0.12065 -0.305054)
			(stroke
				(width 0.1)
				(type default)
			)
			(layer "F.Fab")
		)
		(fp_line
			(start -0.12065 -0.305054)
			(end -0.12065 -0.2794)
			(stroke
				(width 0.1)
				(type default)
			)
			(layer "F.Fab")
		)
		(pad "1" smd circle
			(at -0.40005 0 270)
			(size 0 0)
			(layers "F.Cu" "F.Mask" "F.Paste")
			(net "P3V3_AUX")
		)
		(pad "2" smd circle
			(at 0.40005 0 270)
			(size 0 0)
			(layers "F.Cu" "F.Mask" "F.Paste")
			(net "GND")
		)
	)
	(footprint ""
		(layer "F.Cu")
		(at 353.36988 -294.01008 180)
		(property "Reference" "C212"
			(at 0 0 180)
			(layer "F.SilkS")
			(hide yes)
			(effects
				(font
					(size 1.27 1.27)
				)
			)
		)
		(property "Value" ""
			(at 0 0 180)
			(layer "F.Fab")
			(effects
				(font
					(size 1.27 1.27)
				)
			)
		)
		(duplicate_pad_numbers_are_jumpers no)
		(fp_line
			(start 1.524 0.762)
			(end -1.524 0.762)
			(stroke
				(width 0.1524)
				(type default)
			)
			(layer "F.SilkS")
		)
		(fp_line
			(start 1.524 -0.762)
			(end 1.524 0.762)
			(stroke
				(width 0.1524)
				(type default)
			)
			(layer "F.SilkS")
		)
		(fp_line
			(start -1.524 0.762)
			(end -1.524 -0.762)
			(stroke
				(width 0.1524)
				(type default)
			)
			(layer "F.SilkS")
		)
		(fp_line
			(start -1.524 -0.762)
			(end 1.524 -0.762)
			(stroke
				(width 0.1524)
				(type default)
			)
			(layer "F.SilkS")
		)
		(fp_line
			(start 1.1049 0.724916)
			(end 1.1049 -0.724916)
			(stroke
				(width 0.1)
				(type default)
			)
			(layer "F.Fab")
		)
		(fp_line
			(start 1.1049 -0.724916)
			(end -1.1049 -0.724916)
			(stroke
				(width 0.1)
				(type default)
			)
			(layer "F.Fab")
		)
		(fp_line
			(start -1.1049 0.724916)
			(end 1.1049 0.724916)
			(stroke
				(width 0.1)
				(type default)
			)
			(layer "F.Fab")
		)
		(fp_line
			(start -1.1049 -0.724916)
			(end -1.1049 0.724916)
			(stroke
				(width 0.1)
				(type default)
			)
			(layer "F.Fab")
		)
		(pad "1" smd rect
			(at -0.889 0)
			(size 1.016 1.27)
			(layers "F.Cu" "F.Mask" "F.Paste")
			(net "PVCCIN_CPU0")
		)
		(pad "2" smd rect
			(at 0.889 0)
			(size 1.016 1.27)
			(layers "F.Cu" "F.Mask" "F.Paste")
			(net "GND")
		)
	)
	(footprint ""
		(layer "F.Cu")
		(at 24.050752 -402.806408 180)
		(property "Reference" "C1881"
			(at 0 0 180)
			(layer "F.SilkS")
			(hide yes)
			(effects
				(font
					(size 1.27 1.27)
				)
			)
		)
		(property "Value" ""
			(at 0 0 180)
			(layer "F.Fab")
			(effects
				(font
					(size 1.27 1.27)
				)
			)
		)
		(duplicate_pad_numbers_are_jumpers no)
		(fp_line
			(start 0.7874 0.4064)
			(end -0.7874 0.4064)
			(stroke
				(width 0.1524)
				(type default)
			)
			(layer "F.SilkS")
		)
		(fp_line
			(start 0.7874 -0.4064)
			(end 0.7874 0.4064)
			(stroke
				(width 0.1524)
				(type default)
			)
			(layer "F.SilkS")
		)
		(fp_line
			(start -0.7874 0.4064)
			(end -0.7874 -0.4064)
			(stroke
				(width 0.1524)
				(type default)
			)
			(layer "F.SilkS")
		)
		(fp_line
			(start -0.7874 -0.4064)
			(end 0.7874 -0.4064)
			(stroke
				(width 0.1524)
				(type default)
			)
			(layer "F.SilkS")
		)
		(fp_line
			(start 0.67945 0.3048)
			(end 0.120396 0.3048)
			(stroke
				(width 0.1)
				(type default)
			)
			(layer "F.Fab")
		)
		(fp_line
			(start 0.67945 -0.3048)
			(end 0.67945 0.3048)
			(stroke
				(width 0.1)
				(type default)
			)
			(layer "F.Fab")
		)
		(fp_line
			(start 0.12065 -0.2794)
			(end 0.12065 -0.3048)
			(stroke
				(width 0.1)
				(type default)
			)
			(layer "F.Fab")
		)
		(fp_line
			(start 0.12065 -0.3048)
			(end 0.67945 -0.3048)
			(stroke
				(width 0.1)
				(type default)
			)
			(layer "F.Fab")
		)
		(fp_line
			(start 0.120396 0.3048)
			(end 0.120396 0.2794)
			(stroke
				(width 0.1)
				(type default)
			)
			(layer "F.Fab")
		)
		(fp_line
			(start 0.120396 0.2794)
			(end -0.12065 0.2794)
			(stroke
				(width 0.1)
				(type default)
			)
			(layer "F.Fab")
		)
		(fp_line
			(start -0.12065 0.3048)
			(end -0.67945 0.3048)
			(stroke
				(width 0.1)
				(type default)
			)
			(layer "F.Fab")
		)
		(fp_line
			(start -0.12065 0.2794)
			(end -0.12065 0.3048)
			(stroke
				(width 0.1)
				(type default)
			)
			(layer "F.Fab")
		)
		(fp_line
			(start -0.12065 -0.2794)
			(end 0.12065 -0.2794)
			(stroke
				(width 0.1)
				(type default)
			)
			(layer "F.Fab")
		)
		(fp_line
			(start -0.12065 -0.305054)
			(end -0.12065 -0.2794)
			(stroke
				(width 0.1)
				(type default)
			)
			(layer "F.Fab")
		)
		(fp_line
			(start -0.67945 0.3048)
			(end -0.67945 -0.305054)
			(stroke
				(width 0.1)
				(type default)
			)
			(layer "F.Fab")
		)
		(fp_line
			(start -0.67945 -0.305054)
			(end -0.12065 -0.305054)
			(stroke
				(width 0.1)
				(type default)
			)
			(layer "F.Fab")
		)
		(pad "1" smd circle
			(at -0.40005 0 180)
			(size 0 0)
			(layers "F.Cu" "F.Mask" "F.Paste")
			(net "GPU_FPGA_READY_ISO")
		)
		(pad "2" smd circle
			(at 0.40005 0 180)
			(size 0 0)
			(layers "F.Cu" "F.Mask" "F.Paste")
			(net "GND")
		)
	)
	(footprint ""
		(layer "F.Cu")
		(at 214.75827 -75.254358 90)
		(property "Reference" "R1353"
			(at 0 0 90)
			(layer "F.SilkS")
			(hide yes)
			(effects
				(font
					(size 1.27 1.27)
				)
			)
		)
		(property "Value" ""
			(at 0 0 90)
			(layer "F.Fab")
			(effects
				(font
					(size 1.27 1.27)
				)
			)
		)
		(duplicate_pad_numbers_are_jumpers no)
		(fp_line
			(start 0.7874 -0.4064)
			(end 0.7874 0.4064)
			(stroke
				(width 0.1524)
				(type default)
			)
			(layer "F.SilkS")
		)
		(fp_line
			(start -0.7874 -0.4064)
			(end 0.7874 -0.4064)
			(stroke
				(width 0.1524)
				(type default)
			)
			(layer "F.SilkS")
		)
		(fp_line
			(start 0.7874 0.4064)
			(end -0.7874 0.4064)
			(stroke
				(width 0.1524)
				(type default)
			)
			(layer "F.SilkS")
		)
		(fp_line
			(start -0.7874 0.4064)
			(end -0.7874 -0.4064)
			(stroke
				(width 0.1524)
				(type default)
			)
			(layer "F.SilkS")
		)
		(fp_line
			(start -0.12065 -0.305054)
			(end -0.12065 -0.2794)
			(stroke
				(width 0.1)
				(type default)
			)
			(layer "F.Fab")
		)
		(fp_line
			(start -0.67945 -0.305054)
			(end -0.12065 -0.305054)
			(stroke
				(width 0.1)
				(type default)
			)
			(layer "F.Fab")
		)
		(fp_line
			(start 0.67945 -0.3048)
			(end 0.67945 0.3048)
			(stroke
				(width 0.1)
				(type default)
			)
			(layer "F.Fab")
		)
		(fp_line
			(start 0.12065 -0.3048)
			(end 0.67945 -0.3048)
			(stroke
				(width 0.1)
				(type default)
			)
			(layer "F.Fab")
		)
		(fp_line
			(start 0.12065 -0.2794)
			(end 0.12065 -0.3048)
			(stroke
				(width 0.1)
				(type default)
			)
			(layer "F.Fab")
		)
		(fp_line
			(start -0.12065 -0.2794)
			(end 0.12065 -0.2794)
			(stroke
				(width 0.1)
				(type default)
			)
			(layer "F.Fab")
		)
		(fp_line
			(start 0.120396 0.2794)
			(end -0.12065 0.2794)
			(stroke
				(width 0.1)
				(type default)
			)
			(layer "F.Fab")
		)
		(fp_line
			(start -0.12065 0.2794)
			(end -0.12065 0.3048)
			(stroke
				(width 0.1)
				(type default)
			)
			(layer "F.Fab")
		)
		(fp_line
			(start 0.67945 0.3048)
			(end 0.120396 0.3048)
			(stroke
				(width 0.1)
				(type default)
			)
			(layer "F.Fab")
		)
		(fp_line
			(start 0.120396 0.3048)
			(end 0.120396 0.2794)
			(stroke
				(width 0.1)
				(type default)
			)
			(layer "F.Fab")
		)
		(fp_line
			(start -0.12065 0.3048)
			(end -0.67945 0.3048)
			(stroke
				(width 0.1)
				(type default)
			)
			(layer "F.Fab")
		)
		(fp_line
			(start -0.67945 0.3048)
			(end -0.67945 -0.305054)
			(stroke
				(width 0.1)
				(type default)
			)
			(layer "F.Fab")
		)
		(pad "1" smd circle
			(at -0.40005 0 90)
			(size 0 0)
			(layers "F.Cu" "F.Mask" "F.Paste")
			(net "RMII_BMC_OCP_TX_EN")
		)
		(pad "2" smd circle
			(at 0.40005 0 90)
			(size 0 0)
			(layers "F.Cu" "F.Mask" "F.Paste")
			(net "GND")
		)
	)
	(footprint ""
		(layer "F.Cu")
		(at 149.25421 -42.488104)
		(property "Reference" "U239"
			(at -4.5593 -1.791208 0)
			(unlocked yes)
			(layer "F.SilkS")
			(effects
				(font
					(size 0.7874 0.5842)
					(thickness 0.1524)
				)
				(justify left)
			)
		)
		(property "Value" ""
			(at 0 0 0)
			(layer "F.Fab")
			(effects
				(font
					(size 1.27 1.27)
				)
			)
		)
		(duplicate_pad_numbers_are_jumpers no)
		(fp_line
			(start -1.400048 1.100074)
			(end -1.400048 -1.100074)
			(stroke
				(width 0.1524)
				(type default)
			)
			(layer "F.SilkS")
		)
		(fp_line
			(start 1.400048 -1.100074)
			(end -1.400048 -1.100074)
			(stroke
				(width 0.1524)
				(type default)
			)
			(layer "F.SilkS")
		)
		(fp_line
			(start 1.400048 -1.100074)
			(end 1.400048 1.100074)
			(stroke
				(width 0.1524)
				(type default)
			)
			(layer "F.SilkS")
		)
		(fp_line
			(start 1.400048 1.100074)
			(end -1.400048 1.100074)
			(stroke
				(width 0.1524)
				(type default)
			)
			(layer "F.SilkS")
		)
		(fp_poly
			(pts
				(xy -1.054608 -1.316482) (xy -1.562608 -2.332482) (xy -0.546608 -2.332482)
			)
			(stroke
				(width 0)
				(type default)
			)
			(fill yes)
			(layer "F.SilkS")
		)
		(fp_line
			(start -0.674878 -1.100074)
			(end 0.674878 -1.100074)
			(stroke
				(width 0.1)
				(type default)
			)
			(layer "F.Fab")
		)
		(fp_line
			(start -0.674878 1.100074)
			(end -0.674878 -1.100074)
			(stroke
				(width 0.1)
				(type default)
			)
			(layer "F.Fab")
		)
		(fp_line
			(start 0.674878 -1.100074)
			(end 0.674878 1.100074)
			(stroke
				(width 0.1)
				(type default)
			)
			(layer "F.Fab")
		)
		(fp_line
			(start 0.674878 1.100074)
			(end -0.674878 1.100074)
			(stroke
				(width 0.1)
				(type default)
			)
			(layer "F.Fab")
		)
		(fp_poly
			(pts
				(xy -1.590548 -0.649986) (xy -2.606548 -1.157986) (xy -2.606548 -0.141986)
			)
			(stroke
				(width 0)
				(type default)
			)
			(fill yes)
			(layer "F.Fab")
		)
		(pad "1" smd rect
			(at -0.94996 -0.649986 270)
			(size 0.4318 0.6096)
			(layers "F.Cu" "F.Mask" "F.Paste")
			(net "PU_BUFFER_HDD_ACTIVITY")
		)
		(pad "2" smd rect
			(at -0.94996 0 270)
			(size 0.4318 0.6096)
			(layers "F.Cu" "F.Mask" "F.Paste")
			(net "LED_HDD_ACTIVITY_N")
		)
		(pad "3" smd rect
			(at -0.94996 0.649986 270)
			(size 0.4318 0.6096)
			(layers "F.Cu" "F.Mask" "F.Paste")
			(net "GND")
		)
		(pad "4" smd rect
			(at 0.94996 0.649986 270)
			(size 0.4318 0.6096)
			(layers "F.Cu" "F.Mask" "F.Paste")
			(net "LED_HDD_ACTIVITY_B_N")
		)
		(pad "5" smd rect
			(at 0.94996 -0.649986 270)
			(size 0.4318 0.6096)
			(layers "F.Cu" "F.Mask" "F.Paste")
			(net "P3V3_AUX")
		)
	)
	(footprint ""
		(layer "F.Cu")
		(at 293.497 -346.700348)
		(property "Reference" "PC620"
			(at 0 0 0)
			(layer "F.SilkS")
			(hide yes)
			(effects
				(font
					(size 1.27 1.27)
				)
			)
		)
		(property "Value" ""
			(at 0 0 0)
			(layer "F.Fab")
			(effects
				(font
					(size 1.27 1.27)
				)
			)
		)
		(duplicate_pad_numbers_are_jumpers no)
		(fp_line
			(start 2.750058 0.999998)
			(end -2.750058 0.999998)
			(stroke
				(width 0.1524)
				(type default)
			)
			(layer "F.SilkS")
		)
		(fp_circle
			(center 0 0.999998)
			(end 2.750058 0.999998)
			(stroke
				(width 0.1524)
				(type default)
			)
			(fill no)
			(layer "F.SilkS")
		)
		(fp_poly
			(pts
				(arc
					(start 2.750058 0.999998)
					(mid 0 3.750056)
					(end -2.750058 0.999998)
				)
			)
			(stroke
				(width 0)
				(type default)
			)
			(fill yes)
			(layer "F.SilkS")
		)
		(fp_circle
			(center 0 0.999998)
			(end 2.750058 0.999998)
			(stroke
				(width 0.1)
				(type default)
			)
			(fill no)
			(layer "F.Fab")
		)
		(pad "1" thru_hole rect
			(at 0 0)
			(size 1.5748 1.5748)
			(drill 1.0668)
			(layers "*.Cu" "*.Mask")
			(remove_unused_layers no)
			(net "PVCCFA_EHV_FIVRA_CPU0")
			(clearance 0)
			(padstack
				(mode front_inner_back)
				(layer "Inner"
					(shape circle)
					(size 1.5748 1.5748)
					(clearance 0)
				)
				(layer "B.Cu"
					(shape rect)
					(size 1.5748 1.5748)
					(clearance 0)
				)
			)
		)
		(pad "2" thru_hole circle
			(at 0 1.999996)
			(size 1.5748 1.5748)
			(drill 1.0668)
			(layers "*.Cu" "*.Mask")
			(remove_unused_layers no)
			(net "GND")
			(clearance 0)
		)
	)
)
